(kicad_pcb
	(version 20260206)
	(generator "pcbnew")
	(generator_version "10.0")
	(general
		(thickness 1.6)
		(legacy_teardrops no)
	)
	(paper "A4")
	(title_block
		(title "Wiwynn_Tioga_Pass_MB.brd")
		(comment 1 "Tioga Pass / footprints 169-174 of 4770")
	)
	(layers
		(0 "F.Cu" signal "TOP")
		(4 "In1.Cu" signal "L2GND")
		(6 "In2.Cu" signal "L3")
		(8 "In3.Cu" signal "L4GND")
		(10 "In4.Cu" signal "L5")
		(12 "In5.Cu" signal "L6GND")
		(14 "In6.Cu" signal "L7VCC")
		(16 "In7.Cu" signal "L8VCC")
		(18 "In8.Cu" signal "L9GND")
		(20 "In9.Cu" signal "L10")
		(22 "In10.Cu" signal "L11GND")
		(24 "In11.Cu" signal "L12")
		(26 "In12.Cu" signal "L13GND")
		(2 "B.Cu" signal "BOTTOM")
		(9 "F.Adhes" user "F.Adhesive")
		(11 "B.Adhes" user "B.Adhesive")
		(13 "F.Paste" user "Package Geometry/Pastemask Top")
		(15 "B.Paste" user "Package Geometry/Pastemask Bottom")
		(5 "F.SilkS" user "Ref Des/Silkscreen Top")
		(7 "B.SilkS" user "Ref Des/Silkscreen Bottom")
		(1 "F.Mask" user "Board Geometry/Soldermask Top")
		(3 "B.Mask" user "Board Geometry/Soldermask Bottom")
		(17 "Dwgs.User" user "User.Drawings")
		(19 "Cmts.User" user "User.Comments")
		(21 "Eco1.User" user "User.Eco1")
		(23 "Eco2.User" user "User.Eco2")
		(25 "Edge.Cuts" user "Board Geometry/Outline")
		(27 "Margin" user)
		(31 "F.CrtYd" user "Package Geometry/Place Bound Top")
		(29 "B.CrtYd" user "Package Geometry/Place Bound Bottom")
		(35 "F.Fab" user "Ref Des/Assembly Top")
		(33 "B.Fab" user "Ref Des/Assembly Bottom")
	)
	(footprint ""
		(layer "F.Cu")
		(at 33.925002 -97.679764 90)
		(property "Reference" "EU1C1"
			(at 3.385566 -0.143002 0)
			(unlocked yes)
			(layer "F.SilkS")
			(effects
				(font
					(size 0.7874 0.5842)
					(thickness 0.1524)
				)
			)
		)
		(property "Value" ""
			(at 0 0 90)
			(layer "F.Fab")
			(effects
				(font
					(size 1.27 1.27)
				)
			)
		)
		(duplicate_pad_numbers_are_jumpers no)
		(fp_line
			(start 2.9718 -3.5052)
			(end 2.9718 3.429)
			(stroke
				(width 0.1524)
				(type default)
			)
			(layer "F.SilkS")
		)
		(fp_line
			(start -3.0099 -3.5052)
			(end 2.9718 -3.5052)
			(stroke
				(width 0.1524)
				(type default)
			)
			(layer "F.SilkS")
		)
		(fp_line
			(start 2.9718 3.429)
			(end -3.0099 3.429)
			(stroke
				(width 0.1524)
				(type default)
			)
			(layer "F.SilkS")
		)
		(fp_line
			(start -3.0099 3.429)
			(end -3.0099 -3.5052)
			(stroke
				(width 0.1524)
				(type default)
			)
			(layer "F.SilkS")
		)
		(fp_circle
			(center -3.057398 -2.678684)
			(end -3.057398 -2.551684)
			(stroke
				(width 0.254)
				(type default)
			)
			(fill no)
			(layer "F.SilkS")
		)
		(fp_poly
			(pts
				(xy -2.9972 -3.4925) (xy -2.9972 -2.6924) (xy -2.1971 -3.4925)
			)
			(stroke
				(width 0)
				(type default)
			)
			(fill yes)
			(layer "F.SilkS")
		)
		(fp_poly
			(pts
				(xy -2.549906 -3.050032) (xy -2.549906 3.050032) (xy 2.549906 3.050032) (xy 2.549906 -3.050032)
			)
			(stroke
				(width 0)
				(type default)
			)
			(fill no)
			(layer "F.CrtYd")
		)
		(fp_line
			(start 2.549906 -3.050032)
			(end 2.549906 3.050032)
			(stroke
				(width 0.1)
				(type default)
			)
			(layer "F.Fab")
		)
		(fp_line
			(start -2.549906 -3.050032)
			(end 2.549906 -3.050032)
			(stroke
				(width 0.1)
				(type default)
			)
			(layer "F.Fab")
		)
		(fp_line
			(start 2.549906 3.050032)
			(end -2.549906 3.050032)
			(stroke
				(width 0.1)
				(type default)
			)
			(layer "F.Fab")
		)
		(fp_line
			(start -2.549906 3.050032)
			(end -2.549906 -3.050032)
			(stroke
				(width 0.1)
				(type default)
			)
			(layer "F.Fab")
		)
		(fp_circle
			(center -3.057398 -2.678684)
			(end -3.057398 -2.551684)
			(stroke
				(width 0.254)
				(type default)
			)
			(fill no)
			(layer "F.Fab")
		)
		(pad "1" smd rect
			(at -2.39522 -2.279904 90)
			(size 0.7112 0.254)
			(layers "F.Cu" "F.Mask" "F.Paste")
			(net "PVSA_CPU1")
		)
		(pad "2" smd rect
			(at -2.39522 -1.83007 90)
			(size 0.7112 0.254)
			(layers "F.Cu" "F.Mask" "F.Paste")
			(net "GND")
		)
		(pad "3" smd rect
			(at -2.39522 -1.379982 90)
			(size 0.7112 0.254)
			(layers "F.Cu" "F.Mask" "F.Paste")
			(net "VR_PVSA_CPU1_VCIN")
		)
		(pad "4" smd rect
			(at -2.39522 -0.929894 90)
			(size 0.7112 0.254)
			(layers "F.Cu" "F.Mask" "F.Paste")
			(net "P5V_STBY")
		)
		(pad "5" smd rect
			(at -2.39522 -0.48006 90)
			(size 0.7112 0.254)
			(layers "F.Cu" "F.Mask" "F.Paste")
			(net "GND")
		)
		(pad "6" smd rect
			(at -2.39522 -0.029972 90)
			(size 0.7112 0.254)
			(layers "F.Cu" "F.Mask" "F.Paste")
			(net "TP_PVSA_CPU1_GL_0")
		)
		(pad "7" smd custom
			(at 0.016764 1.145032 90)
			(size 0.53975 0.53975)
			(layers "F.Cu" "F.Mask" "F.Paste")
			(net "GND")
			(options
				(clearance outline)
				(anchor circle)
			)
			(primitives
				(gr_poly
					(pts
						(xy -2.7051 1.0795) (xy -2.7051 -0.3683) (xy -0.9271 -0.3683) (xy -0.9271 -1.0795) (xy 2.7051 -1.0795)
						(xy 2.7051 1.0795)
					)
					(width 0)
					(fill yes)
				)
			)
		)
		(pad "10" smd rect
			(at -0.008382 2.874772 90)
			(size 4.3434 0.6096)
			(layers "F.Cu" "F.Mask" "F.Paste")
			(net "VR_PVSA_CPU1_PHASE_SW")
		)
		(pad "25" smd rect
			(at 1.548384 -1.283208 90)
			(size 2.3368 2.0066)
			(layers "F.Cu" "F.Mask" "F.Paste")
			(net "VR_FET_SW_P12V_STBY_PVCCIN_CPU1")
		)
		(pad "30" smd rect
			(at 2.050034 -2.895092 90)
			(size 0.254 0.7112)
			(layers "F.Cu" "F.Mask" "F.Paste")
			(net "VR_FET_SW_P12V_STBY_PVCCIN_CPU1")
		)
		(pad "31" smd rect
			(at 1.599946 -2.895092 90)
			(size 0.254 0.7112)
			(layers "F.Cu" "F.Mask" "F.Paste")
			(net "Net_295")
		)
		(pad "32" smd rect
			(at 1.150112 -2.895092 90)
			(size 0.254 0.7112)
			(layers "F.Cu" "F.Mask" "F.Paste")
			(net "VR_PVSA_CPU1_PHASE")
		)
		(pad "33" smd rect
			(at 0.700024 -2.895092 90)
			(size 0.254 0.7112)
			(layers "F.Cu" "F.Mask" "F.Paste")
			(net "VR_PVSA_CPU1_BOOT_R")
		)
		(pad "34" smd rect
			(at 0.249936 -2.895092 90)
			(size 0.254 0.7112)
			(layers "F.Cu" "F.Mask" "F.Paste")
			(net "VR_PVSA_CPU1_PWM")
		)
		(pad "35" smd rect
			(at -0.199898 -2.895092 90)
			(size 0.254 0.7112)
			(layers "F.Cu" "F.Mask" "F.Paste")
			(net "P5V_STBY")
		)
		(pad "36" smd rect
			(at -0.649986 -2.895092 90)
			(size 0.254 0.7112)
			(layers "F.Cu" "F.Mask" "F.Paste")
			(net "A_TSENSE_PVSA_CPU1")
		)
		(pad "37" smd rect
			(at -1.100074 -2.895092 90)
			(size 0.254 0.7112)
			(layers "F.Cu" "F.Mask" "F.Paste")
			(net "VR_PVSA_CPU1_OCSET")
		)
		(pad "38" smd rect
			(at -1.549908 -2.895092 90)
			(size 0.254 0.7112)
			(layers "F.Cu" "F.Mask" "F.Paste")
			(net "ISENSE_PVSA_CPU1_IMON")
		)
		(pad "39" smd rect
			(at -1.999996 -2.895092 90)
			(size 0.254 0.7112)
			(layers "F.Cu" "F.Mask" "F.Paste")
			(net "VR_PVSA_CPU1_BIREF1")
		)
		(pad "40" smd rect
			(at -0.871728 -1.283208 90)
			(size 1.8034 2.0066)
			(layers "F.Cu" "F.Mask" "F.Paste")
			(net "GND")
		)
		(pad "41" smd rect
			(at -1.533906 0.247904 90)
			(size 0.508 0.3556)
			(layers "F.Cu" "F.Mask" "F.Paste")
			(net "TP_PVSA_CPU1_GL_1")
		)
	)
	(footprint ""
		(layer "F.Cu")
		(at 414.8328 -113.2332 90)
		(property "Reference" "R2M2"
			(at 0 0 90)
			(layer "F.SilkS")
			(hide yes)
			(effects
				(font
					(size 1.27 1.27)
				)
			)
		)
		(property "Value" ""
			(at 0 0 90)
			(layer "F.Fab")
			(effects
				(font
					(size 1.27 1.27)
				)
			)
		)
		(duplicate_pad_numbers_are_jumpers no)
		(fp_poly
			(pts
				(xy -0.2794 -0.1016) (xy 0.2794 -0.1016) (xy 0.2794 0.9906) (xy -0.2794 0.9906)
			)
			(stroke
				(width 0)
				(type default)
			)
			(fill no)
			(layer "F.CrtYd")
		)
		(fp_line
			(start 0.2794 -0.1016)
			(end -0.2794 -0.1016)
			(stroke
				(width 0.1)
				(type default)
			)
			(layer "F.Fab")
		)
		(fp_line
			(start -0.2794 -0.1016)
			(end -0.2794 0.9906)
			(stroke
				(width 0.1)
				(type default)
			)
			(layer "F.Fab")
		)
		(fp_line
			(start 0.2794 0.9906)
			(end 0.2794 -0.1016)
			(stroke
				(width 0.1)
				(type default)
			)
			(layer "F.Fab")
		)
		(fp_line
			(start -0.2794 0.9906)
			(end 0.2794 0.9906)
			(stroke
				(width 0.1)
				(type default)
			)
			(layer "F.Fab")
		)
		(pad "1" smd rect
			(at 0 0 90)
			(size 0.508 0.508)
			(layers "F.Cu" "F.Mask" "F.Paste")
			(net "P3V3_STBY")
		)
		(pad "2" smd rect
			(at 0 0.889 90)
			(size 0.508 0.508)
			(layers "F.Cu" "F.Mask" "F.Paste")
			(net "FM_ADR_SMI_GPIO_N")
		)
		(zone
			(layer "F.Cu")
			(hatch none 0.5)
			(connect_pads
				(clearance 0)
			)
			(min_thickness 0.25)
			(keepout
				(tracks allowed)
				(vias not_allowed)
				(pads allowed)
				(copperpour not_allowed)
				(footprints allowed)
			)
			(placement
				(enabled no)
				(sheetname "")
			)
			(fill
				(thermal_gap 0.5)
				(thermal_bridge_width 0.5)
				(island_removal_mode 0)
			)
			(polygon
				(pts
					(xy 415.0868 -112.9792) (xy 415.0868 -113.4872) (xy 415.4678 -113.4872) (xy 415.4678 -112.9792)
				)
			)
		)
		(zone
			(layer "F.Cu")
			(hatch none 0.5)
			(connect_pads
				(clearance 0)
			)
			(min_thickness 0.25)
			(keepout
				(tracks not_allowed)
				(vias allowed)
				(pads allowed)
				(copperpour not_allowed)
				(footprints allowed)
			)
			(placement
				(enabled no)
				(sheetname "")
			)
			(fill
				(thermal_gap 0.5)
				(thermal_bridge_width 0.5)
				(island_removal_mode 0)
			)
			(polygon
				(pts
					(xy 415.4678 -112.9792) (xy 415.4678 -113.4872) (xy 415.0868 -113.4872) (xy 415.0868 -112.9792)
				)
			)
		)
	)
	(footprint ""
		(layer "F.Cu")
		(at 391.414 -71.9455)
		(property "Reference" "R7E12"
			(at 0 0 0)
			(layer "F.SilkS")
			(hide yes)
			(effects
				(font
					(size 1.27 1.27)
				)
			)
		)
		(property "Value" ""
			(at 0 0 0)
			(layer "F.Fab")
			(effects
				(font
					(size 1.27 1.27)
				)
			)
		)
		(duplicate_pad_numbers_are_jumpers no)
		(fp_poly
			(pts
				(xy -0.2794 -0.1016) (xy 0.2794 -0.1016) (xy 0.2794 0.9906) (xy -0.2794 0.9906)
			)
			(stroke
				(width 0)
				(type default)
			)
			(fill no)
			(layer "F.CrtYd")
		)
		(fp_line
			(start -0.2794 -0.1016)
			(end -0.2794 0.9906)
			(stroke
				(width 0.1)
				(type default)
			)
			(layer "F.Fab")
		)
		(fp_line
			(start -0.2794 0.9906)
			(end 0.2794 0.9906)
			(stroke
				(width 0.1)
				(type default)
			)
			(layer "F.Fab")
		)
		(fp_line
			(start 0.2794 -0.1016)
			(end -0.2794 -0.1016)
			(stroke
				(width 0.1)
				(type default)
			)
			(layer "F.Fab")
		)
		(fp_line
			(start 0.2794 0.9906)
			(end 0.2794 -0.1016)
			(stroke
				(width 0.1)
				(type default)
			)
			(layer "F.Fab")
		)
		(pad "1" smd rect
			(at 0 0)
			(size 0.508 0.508)
			(layers "F.Cu" "F.Mask" "F.Paste")
			(net "P5V_STBY")
		)
		(pad "2" smd rect
			(at 0 0.889)
			(size 0.508 0.508)
			(layers "F.Cu" "F.Mask" "F.Paste")
			(net "PWRGD_P5V_STBY_R")
		)
		(zone
			(layer "F.Cu")
			(hatch none 0.5)
			(connect_pads
				(clearance 0)
			)
			(min_thickness 0.25)
			(keepout
				(tracks allowed)
				(vias not_allowed)
				(pads allowed)
				(copperpour not_allowed)
				(footprints allowed)
			)
			(placement
				(enabled no)
				(sheetname "")
			)
			(fill
				(thermal_gap 0.5)
				(thermal_bridge_width 0.5)
				(island_removal_mode 0)
			)
			(polygon
				(pts
					(xy 391.16 -71.6915) (xy 391.668 -71.6915) (xy 391.668 -71.3105) (xy 391.16 -71.3105)
				)
			)
		)
		(zone
			(layer "F.Cu")
			(hatch none 0.5)
			(connect_pads
				(clearance 0)
			)
			(min_thickness 0.25)
			(keepout
				(tracks not_allowed)
				(vias allowed)
				(pads allowed)
				(copperpour not_allowed)
				(footprints allowed)
			)
			(placement
				(enabled no)
				(sheetname "")
			)
			(fill
				(thermal_gap 0.5)
				(thermal_bridge_width 0.5)
				(island_removal_mode 0)
			)
			(polygon
				(pts
					(xy 391.16 -71.3105) (xy 391.668 -71.3105) (xy 391.668 -71.6915) (xy 391.16 -71.6915)
				)
			)
		)
	)
	(footprint ""
		(layer "F.Cu")
		(at 496.686332 -22.354794 90)
		(property "Reference" "C7E6"
			(at 0 0 90)
			(layer "F.SilkS")
			(hide yes)
			(effects
				(font
					(size 1.27 1.27)
				)
			)
		)
		(property "Value" ""
			(at 0 0 90)
			(layer "F.Fab")
			(effects
				(font
					(size 1.27 1.27)
				)
			)
		)
		(duplicate_pad_numbers_are_jumpers no)
		(fp_rect
			(start -0.7239 1.9939)
			(end 0.7239 -0.2159)
			(stroke
				(width 0)
				(type default)
			)
			(fill no)
			(layer "F.CrtYd")
		)
		(fp_line
			(start 0.7239 -0.2159)
			(end -0.7239 -0.2159)
			(stroke
				(width 0.1)
				(type default)
			)
			(layer "F.Fab")
		)
		(fp_line
			(start -0.7239 -0.2159)
			(end -0.7239 1.9939)
			(stroke
				(width 0.1)
				(type default)
			)
			(layer "F.Fab")
		)
		(fp_line
			(start 0.7239 1.9939)
			(end 0.7239 -0.2159)
			(stroke
				(width 0.1)
				(type default)
			)
			(layer "F.Fab")
		)
		(fp_line
			(start -0.7239 1.9939)
			(end 0.7239 1.9939)
			(stroke
				(width 0.1)
				(type default)
			)
			(layer "F.Fab")
		)
		(pad "1" smd rect
			(at 0 0 90)
			(size 1.27 1.016)
			(layers "F.Cu" "F.Mask" "F.Paste")
			(net "P12V_STBY")
		)
		(pad "2" smd rect
			(at 0 1.778 90)
			(size 1.27 1.016)
			(layers "F.Cu" "F.Mask" "F.Paste")
			(net "GND")
		)
		(zone
			(layer "F.Cu")
			(hatch none 0.5)
			(connect_pads
				(clearance 0)
			)
			(min_thickness 0.25)
			(keepout
				(tracks not_allowed)
				(vias allowed)
				(pads allowed)
				(copperpour not_allowed)
				(footprints allowed)
			)
			(placement
				(enabled no)
				(sheetname "")
			)
			(fill
				(thermal_gap 0.5)
				(thermal_bridge_width 0.5)
				(island_removal_mode 0)
			)
			(polygon
				(pts
					(xy 497.956332 -21.719794) (xy 497.956332 -22.989794) (xy 497.194332 -22.989794) (xy 497.194332 -21.719794)
				)
			)
		)
	)
	(footprint ""
		(layer "F.Cu")
		(at 371.2718 -101.346)
		(property "Reference" "R7C5"
			(at 0 0 0)
			(layer "F.SilkS")
			(hide yes)
			(effects
				(font
					(size 1.27 1.27)
				)
			)
		)
		(property "Value" ""
			(at 0 0 0)
			(layer "F.Fab")
			(effects
				(font
					(size 1.27 1.27)
				)
			)
		)
		(duplicate_pad_numbers_are_jumpers no)
		(fp_poly
			(pts
				(xy -0.2794 -0.1016) (xy 0.2794 -0.1016) (xy 0.2794 0.9906) (xy -0.2794 0.9906)
			)
			(stroke
				(width 0)
				(type default)
			)
			(fill no)
			(layer "F.CrtYd")
		)
		(fp_line
			(start -0.2794 -0.1016)
			(end -0.2794 0.9906)
			(stroke
				(width 0.1)
				(type default)
			)
			(layer "F.Fab")
		)
		(fp_line
			(start -0.2794 0.9906)
			(end 0.2794 0.9906)
			(stroke
				(width 0.1)
				(type default)
			)
			(layer "F.Fab")
		)
		(fp_line
			(start 0.2794 -0.1016)
			(end -0.2794 -0.1016)
			(stroke
				(width 0.1)
				(type default)
			)
			(layer "F.Fab")
		)
		(fp_line
			(start 0.2794 0.9906)
			(end 0.2794 -0.1016)
			(stroke
				(width 0.1)
				(type default)
			)
			(layer "F.Fab")
		)
		(pad "1" smd rect
			(at 0 0)
			(size 0.508 0.508)
			(layers "F.Cu" "F.Mask" "F.Paste")
			(net "P3V3_STBY")
		)
		(pad "2" smd rect
			(at 0 0.889)
			(size 0.508 0.508)
			(layers "F.Cu" "F.Mask" "F.Paste")
			(net "FM_SINT_PRSNT_N")
		)
		(zone
			(layer "F.Cu")
			(hatch none 0.5)
			(connect_pads
				(clearance 0)
			)
			(min_thickness 0.25)
			(keepout
				(tracks allowed)
				(vias not_allowed)
				(pads allowed)
				(copperpour not_allowed)
				(footprints allowed)
			)
			(placement
				(enabled no)
				(sheetname "")
			)
			(fill
				(thermal_gap 0.5)
				(thermal_bridge_width 0.5)
				(island_removal_mode 0)
			)
			(polygon
				(pts
					(xy 371.0178 -101.092) (xy 371.5258 -101.092) (xy 371.5258 -100.711) (xy 371.0178 -100.711)
				)
			)
		)
		(zone
			(layer "F.Cu")
			(hatch none 0.5)
			(connect_pads
				(clearance 0)
			)
			(min_thickness 0.25)
			(keepout
				(tracks not_allowed)
				(vias allowed)
				(pads allowed)
				(copperpour not_allowed)
				(footprints allowed)
			)
			(placement
				(enabled no)
				(sheetname "")
			)
			(fill
				(thermal_gap 0.5)
				(thermal_bridge_width 0.5)
				(island_removal_mode 0)
			)
			(polygon
				(pts
					(xy 371.0178 -100.711) (xy 371.5258 -100.711) (xy 371.5258 -101.092) (xy 371.0178 -101.092)
				)
			)
		)
	)
	(footprint ""
		(layer "F.Cu")
		(at 490.474 -37.338 180)
		(property "Reference" "R25W126"
			(at -0.8382 -0.67818 180)
			(unlocked yes)
			(layer "F.SilkS")
			(effects
				(font
					(size 0.4064 0.254)
					(thickness 0.1524)
				)
				(justify left)
			)
		)
		(property "Value" ""
			(at 0 0 180)
			(layer "F.Fab")
			(effects
				(font
					(size 1.27 1.27)
				)
			)
		)
		(duplicate_pad_numbers_are_jumpers no)
		(fp_poly
			(pts
				(xy -0.2794 -0.1016) (xy 0.2794 -0.1016) (xy 0.2794 0.9906) (xy -0.2794 0.9906)
			)
			(stroke
				(width 0)
				(type default)
			)
			(fill no)
			(layer "F.CrtYd")
		)
		(fp_line
			(start 0.2794 0.9906)
			(end 0.2794 -0.1016)
			(stroke
				(width 0.1)
				(type default)
			)
			(layer "F.Fab")
		)
		(fp_line
			(start 0.2794 -0.1016)
			(end -0.2794 -0.1016)
			(stroke
				(width 0.1)
				(type default)
			)
			(layer "F.Fab")
		)
		(fp_line
			(start -0.2794 0.9906)
			(end 0.2794 0.9906)
			(stroke
				(width 0.1)
				(type default)
			)
			(layer "F.Fab")
		)
		(fp_line
			(start -0.2794 -0.1016)
			(end -0.2794 0.9906)
			(stroke
				(width 0.1)
				(type default)
			)
			(layer "F.Fab")
		)
		(pad "1" smd rect
			(at 0 0 180)
			(size 0.508 0.508)
			(layers "F.Cu" "F.Mask" "F.Paste")
			(net "V_IO_B_J")
		)
		(pad "2" smd rect
			(at 0 0.889 180)
			(size 0.508 0.508)
			(layers "F.Cu" "F.Mask" "F.Paste")
			(net "GND")
		)
		(zone
			(layer "F.Cu")
			(hatch none 0.5)
			(connect_pads
				(clearance 0)
			)
			(min_thickness 0.25)
			(keepout
				(tracks not_allowed)
				(vias allowed)
				(pads allowed)
				(copperpour not_allowed)
				(footprints allowed)
			)
			(placement
				(enabled no)
				(sheetname "")
			)
			(fill
				(thermal_gap 0.5)
				(thermal_bridge_width 0.5)
				(island_removal_mode 0)
			)
			(polygon
				(pts
					(xy 490.728 -37.973) (xy 490.22 -37.973) (xy 490.22 -37.592) (xy 490.728 -37.592)
				)
			)
		)
		(zone
			(layer "F.Cu")
			(hatch none 0.5)
			(connect_pads
				(clearance 0)
			)
			(min_thickness 0.25)
			(keepout
				(tracks allowed)
				(vias not_allowed)
				(pads allowed)
				(copperpour not_allowed)
				(footprints allowed)
			)
			(placement
				(enabled no)
				(sheetname "")
			)
			(fill
				(thermal_gap 0.5)
				(thermal_bridge_width 0.5)
				(island_removal_mode 0)
			)
			(polygon
				(pts
					(xy 490.728 -37.592) (xy 490.22 -37.592) (xy 490.22 -37.973) (xy 490.728 -37.973)
				)
			)
		)
	)
)
